# TIMECARD (Time Appliance Project (Time Card)) — schematic parts with pin connectivity, parts 331–426 of 1119; source: Cadence DE-HDL packaged netlist (pstxprt.dat, pstxnet.dat, pstchip.dat)

DS6  OPTICAL  pkg SMC_DS_063X031_V4  page 26 : A = UNNAMED_14_OPTICAL_I140_A ; C = SG
DS7  OPTICAL  pkg SMC_DS_063X031_V4  page 26 : A = UNNAMED_14_OPTICAL_I141_A ; C = SG
DS8  OPTICAL  pkg SMC_DS_063X031_V4  page 26 : A = UNNAMED_14_OPTICAL_I142_A ; C = SG
DS9  OPTICAL  pkg SMC_DS_063X031_V4  page 26 : A = UNNAMED_14_OPTICAL_I292_A ; C = SG
DS10  OPTICAL  pkg SMC_DS_063X031_V4  page 26 : A = UNNAMED_14_OPTICAL_I138_A ; C = FPGA_USR_LED1
DS11  OPTICAL  pkg SMC_DS_063X031_V4  page 26 : A = UNNAMED_14_OPTICAL_I139_A ; C = FPGA_USR_LED0
DS12  OPTICAL  pkg SMC_DS_063X031_V4  page 26 : A = UNNAMED_14_OPTICAL_I289_A ; C = SG

DS14  LED_4P_V14  pkg SMC_DS4_098X039  page 26
  1  \1\  BI  = UNNAMED_14_LED4PV14_I265_1
  2  \2\  BI  = XP3R3V_FPGA
  3  \3\  BI  = UNNAMED_14_LED4PV14_I265_3
  4  \4\  BI  = UNNAMED_14_LED4PV14_I265_4

DS15  LED_4P_V14  pkg SMC_DS4_098X039  page 26
  1  \1\  BI  = UNNAMED_14_LED4PV14_I266_1
  2  \2\  BI  = XP3R3V_FPGA
  3  \3\  BI  = UNNAMED_14_LED4PV14_I266_3
  4  \4\  BI  = UNNAMED_14_LED4PV14_I266_4

DS16  LED_4P_V14  pkg SMC_DS4_098X039  page 26
  1  \1\  BI  = UNNAMED_14_LED4PV14_I267_1
  2  \2\  BI  = XP3R3V_FPGA
  3  \3\  BI  = UNNAMED_14_LED4PV14_I267_3
  4  \4\  BI  = UNNAMED_14_LED4PV14_I267_4

DS17  LED_4P_V14  pkg SMC_DS4_098X039  page 26
  1  \1\  BI  = UNNAMED_14_LED4PV14_I268_1
  2  \2\  BI  = XP3R3V_FPGA
  3  \3\  BI  = UNNAMED_14_LED4PV14_I268_3
  4  \4\  BI  = UNNAMED_14_LED4PV14_I268_4

DS18  LED_4P_V14  pkg SMC_DS4_098X039  page 26
  1  \1\  BI  = UNNAMED_14_LED4PV14_I269_1
  2  \2\  BI  = XP3R3V_FPGA
  3  \3\  BI  = UNNAMED_14_LED4PV14_I269_3
  4  \4\  BI  = UNNAMED_14_LED4PV14_I269_4

DS19  OPTICAL  pkg SMC_DS_063X031_V4  page 26 : A = UNNAMED_14_OPTICAL_I191_A ; C = SG
DS20  OPTICAL  pkg SMC_DS_063X031_V4  page 26 : A = UNNAMED_14_OPTICAL_I194_A ; C = SG
FU1  FUSE  2.5A  pkg SMC_0603R_H022  page 27 : 1 = XP12R0V_IN ; 2 = XP12R0V
FU3  FUSE  1A  pkg SMC_0603R_H024  page 21 : 1 = UNNAMED_527_FUSE_I244_1 ; 2 = XP5R0V_MAC_USB

GF1  CONN_64P_GF  pkg S_M_EF64_PCIE_P0394_V1  page 9
  A1  \prsnt1*\  BI  = CARD_PRESENT
  A2  P_12V3  POWER  = XP12R0V_PCIE
  A3  P_12V5  POWER  = XP12R0V_PCIE
  A4  GND2  GROUND  = SG
  A5  JTAG2  BI  = PCIE_CONN_TCK
  A6  JTAG3  BI  = PCIE_CONN_TDI
  A7  JTAG4  BI  = PCIE_CONN_TDO
  A8  JTAG5  BI  = PCIE_CONN_TMS
  A9  P_3V3_2  POWER  = XP3R3V_PCIE
  A10  P_3V3_3  POWER  = XP3R3V_PCIE
  A11  \perst*\  BI  = PCIE_CONN_PERST_N
  A12  GND4  GROUND  = SG
  A13  REFCLK_P  BI  = C_PCIEREFCLKP
  A14  REFCLK_N  BI  = C_PCIEREFCLKN
  A15  GND6  GROUND  = SG
  A16  PERP0  BI  = C_CPU_RX_PCIE_MGT0_TXP
  A17  PERN0  BI  = C_CPU_RX_PCIE_MGT0_TXN
  A18  GND8  GROUND  = SG
  A19  RSVD2  BI  = NC
  A20  GND10  GROUND  = SG
  A21  PERP1  BI  = C_CPU_RX_PCIE_MGT1_TXP
  A22  PERN1  BI  = C_CPU_RX_PCIE_MGT1_TXN
  A23  GND13  GROUND  = SG
  A24  GND14  GROUND  = SG
  A25  PERP2  BI  = C_CPU_RX_PCIE_MGT2_TXP
  A26  PERN2  BI  = C_CPU_RX_PCIE_MGT2_TXN
  A27  GND18  GROUND  = SG
  A28  GND19  GROUND  = SG
  A29  PERP3  BI  = C_CPU_RX_PCIE_MGT3_TXP
  A30  PERN3  BI  = C_CPU_RX_PCIE_MGT3_TXN
  A31  GND21  GROUND  = SG
  A32  RSVD4  BI  = NC
  B1  P_12V1  POWER  = XP12R0V_PCIE
  B2  P_12V2  POWER  = XP12R0V_PCIE
  B3  P_12V4  POWER  = XP12R0V_PCIE
  B4  GND1  GROUND  = SG
  B5  SMCLK  BI  = PCIE_CONN_SMCLK
  B6  SMDAT  BI  = PCIE_CONN_SMDAT
  B7  GND3  GROUND  = SG
  B8  P_3V3_1  POWER  = XP3R3V_PCIE
  B9  JTAG1  BI  = NC
  B10  P_3V3AUX  POWER  = XP3R3V_AUX_PCIE
  B11  \wake*\  BI  = NC
  B12  RSVD1  BI  = NC
  B13  GND5  GROUND  = SG
  B14  PETP0  BI  = CPU_TX_PCIE_MGT_0_RXP
  B15  PETN0  BI  = CPU_TX_PCIE_MGT_0_RXN
  B16  GND7  GROUND  = SG
  B17  \prsnt2_1*\  BI  = UNNAMED_3_CONN64PGF_I61_PRSNT21
  B18  GND9  GROUND  = SG
  B19  PETP1  BI  = CPU_TX_PCIE_MGT_1_RXP
  B20  PETN1  BI  = CPU_TX_PCIE_MGT_1_RXN
  B21  GND11  GROUND  = SG
  B22  GND12  GROUND  = SG
  B23  PETP2  BI  = CPU_TX_PCIE_MGT_2_RXP
  B24  PETN2  BI  = CPU_TX_PCIE_MGT_2_RXN
  B25  GND15  GROUND  = SG
  B26  GND17  GROUND  = SG
  B27  PETP3  BI  = CPU_TX_PCIE_MGT_3_RXP
  B28  PETN3  BI  = CPU_TX_PCIE_MGT_3_RXN
  B29  GND20  GROUND  = SG
  B30  RSVD3  BI  = NC
  B31  \prsnt2_2*\  BI  = UNNAMED_3_CONN64PGF_I61_PRSNT22
  B32  GND22  GROUND  = SG

J1  CONN_JACK_1P_GH4_S_TH  2081680-1  pkg P_F_JACK_1P_GH4_RA_P200  page 23
  1  \1\  BI  = SMA3_SIG_IO_CONN
  GH1  GH1  BI  = SG
  GH2  GH2  BI  = SG
  GH3  GH3  BI  = SG
  GH4  GH4  BI  = SG

J2  CONN_JACK_1P_GH4_S_TH  2081680-1  pkg P_F_JACK_1P_GH4_RA_P200  page 23
  1  \1\  BI  = SMA4_SIG_IO_CONN
  GH1  GH1  BI  = SG
  GH2  GH2  BI  = SG
  GH3  GH3  BI  = SG
  GH4  GH4  BI  = SG

J3  CONN_JACK_1P_GH4_S_TH  2081680-1  pkg P_F_JACK_1P_GH4_RA_P200  page 23
  1  \1\  BI  = SMA1_SIG_IO_CONN
  GH1  GH1  BI  = SG
  GH2  GH2  BI  = SG
  GH3  GH3  BI  = SG
  GH4  GH4  BI  = SG

J4  CONN_JACK_1P_GH4_S_TH  2081680-1  pkg P_F_JACK_1P_GH4_RA_P200  page 23
  1  \1\  BI  = SMA2_SIG_IO_CONN
  GH1  GH1  BI  = SG
  GH2  GH2  BI  = SG
  GH3  GH3  BI  = SG
  GH4  GH4  BI  = SG

J5  CONN_HDR_2X6_F_S_SMT  SMH-106-02-L-D-TR  pkg S_F_H_2X6_RA_P100  page 25
  1  \1\  BI  = UNNAMED_16_CONNHDR2X6FSSMT_I161
  2  \2\  BI  = UNNAMED_16_CONNHDR2X6FSSMT_I1_1
  3  \3\  BI  = UNNAMED_16_CONNHDR2X6FSSMT_I1_2
  4  \4\  BI  = UNNAMED_16_CONNHDR2X6FSSMT_I1_3
  5  \5\  BI  = UNNAMED_16_CONNHDR2X6FSSMT_I1_6
  6  \6\  BI  = UNNAMED_16_CONNHDR2X6FSSMT_I1_7
  7  \7\  BI  = UNNAMED_16_CONNHDR2X6FSSMT_I1_4
  8  \8\  BI  = UNNAMED_16_CONNHDR2X6FSSMT_I1_5
  9  \9\  BI  = SG
  10  \10\  BI  = SG
  11  \11\  BI  = XP3R3V_FPGA
  12  \12\  BI  = XP3R3V_FPGA

J9  CONN_HDR_2X2_M_S_SMT  pkg S_M_H_2X2_S_P100_V3  page 16
  1  \1\  BI  = UNNAMED_5_CONNHDR2X2MSSMT_I126_
  2  \2\  BI  = EEPROM_SDA
  3  \3\  BI  = UNNAMED_5_CONNHDR2X2MSSMT_I12_1
  4  \4\  BI  = EEPROM_SCL

J10  G200_10283_01  pkg S_M_DIL_2X5_P100_V1  page 24
  1  \1\  BI  = FT4232_CHD_TX
  2  \2\  BI  = DBG_UART_MAC_RX
  3  \3\  BI  = FT4232_CHD_TX
  4  \4\  BI  = DBG_UART_GPS_RXD
  5  \5\  BI  = FT4232_CHD_RX
  6  \6\  BI  = DBG_UART_MAC_TX
  7  \7\  BI  = FT4232_CHD_RX
  8  \8\  BI  = DBG_UART_GPS_TXD
  9  \9\  BI  = SG
  10  \10\  BI  = FPGA_CFG_INIT_N

J11  CONN_USB_1X5_G2_GH4_F_RA_SMT  1050171001  pkg S_F_USB_1X5_G2_GH4_RA_P0256  page 21
  1  \1\  BI  = XP5R0V_USB_CONN
  2  \2\  BI  = CONN_MICRO_USB_DM
  3  \3\  BI  = CONN_MICRO_USB_DP
  4  \4\  BI  = NC
  5  \5\  BI  = SG
  G1  G1  GROUND  = SG
  G2  G2  GROUND  = SG
  GH1  GH1  BI  = SG
  GH2  GH2  BI  = SG
  GH3  GH3  BI  = SG
  GH4  GH4  BI  = SG

J13  CONN_USB_14P_GH4_F_RA_TH  2169890002  pkg P_F_USB_2X7_GH4_RA_P035_PIH  page 24
  A1  GND_1  GROUND  = SG
  A4  VBUS_1  POWER  = XP5R0V_FT4232
  A5  CC1  BI  = UNNAMED_524_CONNUSB14PGH4FRATH_
  A6  D1_P  BI  = FT_USB_DP
  A7  D1_N  BI  = FT_USB_DM
  A9  VBUS_2  POWER  = XP5R0V_FT4232
  A12  GND_2  GROUND  = SG
  B1  GND_3  GROUND  = SG
  B4  VBUS_3  POWER  = XP5R0V_FT4232
  B5  CC2  BI  = UNNAMED_524_CONNUSB14PGH4FRAT_1
  B6  D2_P  BI  = FT_USB_DP
  B7  D2_N  BI  = FT_USB_DM
  B9  VBUS_4  POWER  = XP5R0V_FT4232
  B12  GND_4  GROUND  = SG
  GH1  GH1  GROUND  = SG
  GH2  GH2  GROUND  = SG
  GH3  GH3  GROUND  = SG
  GH4  GH4  GROUND  = SG

J14  G200_10283_01  pkg S_M_DIL_2X5_P100_V1  page 10
  1  \1\  BI  = FT4232_FPGA_TCK
  2  \2\  BI  = SG
  3  \3\  BI  = FT4232_FPGA_TDO
  4  \4\  BI  = UNNAMED_127_G2001028301_I427_4
  5  \5\  BI  = FT4232_FPGA_TMS
  6  \6\  BI  = NC
  7  \7\  BI  = NC
  8  \8\  BI  = NC
  9  \9\  BI  = FT4232_FPGA_TDI
  10  \10\  BI  = SG

J17  CONN_HDR_2X2_M_S_SMT  pkg S_M_H_2X2_S_P100_V3  page 16
  1  \1\  BI  = SN_EEPROM_WP
  2  \2\  BI  = SG
  3  \3\  BI  = SEC_EEPROM_WP
  4  \4\  BI  = SG

J18  CONN_HDR_1X3_M_S_SMT  pkg S_M_H_3P_S_P058  page 21
  1  \1\  BI  = SG
  2  \2\  BI  = SMA_ANALOG_TUNING_IN
  3  \3\  BI  = SG

L1  INDUCTOR_2  4.7UH 20%  pkg SMC_L_287X268_V3  page 32 : 1 = XP5R0V_SW ; 2 = XP5R0V
L2  INDUCTOR_2  4.7UH 20%  pkg SMC_L_287X268_V3  page 28 : 1 = XP3R3V_SW ; 2 = XP3R3V
L3  FERRITEBEAD  26OHM 25%  pkg SMC_0603R_H030  page 21 : 1 = XP5R0V_MAC ; 2 = XP5R0V
L4  FERRITEBEAD  600OHM 25%  pkg SMC_0603R_H037  page 24 : 1 = XP3R3V_FT4232 ; 2 = XP3R3V_VPLL
L5  INDUCTOR_2  1.0UH 20%  pkg SMC_L_287X260_V1_H197  page 29 : 1 = XP1R0V_SW ; 2 = XP1R0V_FPGA
L6  FERRITEBEAD  26OHM 25%  pkg SMC_0603R_H030  page 30 : 1 = XP3R3V ; 2 = XP1R8V_VIN
L7  FERRITEBEAD  26OHM 25%  pkg SMC_0603R_H030  page 32 : 1 = XP12R0V ; 2 = VIN_XP5R0V
L8  FERRITEBEAD  26OHM 25%  pkg SMC_0603R_H030  page 28 : 1 = XP12R0V ; 2 = VIN_XP3R3
L9  FERRITEBEAD  26OHM 25%  pkg SMC_0603R_H030  page 29 : 1 = XP12R0V ; 2 = VIN_XP1R0V
L10  FERRITEBEAD  600OHM 25%  pkg SMC_0603R_H037  page 15 : 1 = VDD3V3_OSC_125M ; 2 = XP3R3V
L11  FERRITEBEAD  26OHM 25%  pkg SMC_0603R_H030  page 30 : 1 = XP3R3V ; 2 = XP1R2V_VIN
L12  FERRITEBEAD  120OHM 25%  pkg SMC_0603R_H030  page 14 : 1 = XP1R0V_FPGA_VCCINT ; 2 = XP1R0V_FPGA
L13  FERRITEBEAD  26OHM 25%  pkg SMC_0603R_H030  page 31 : 1 = XP3R3V ; 2 = UNNAMED_515_CAPACITOR_I130_1
L14  FERRITEBEAD  600OHM 25%  pkg SMC_0603R_H037  page 15 : 1 = VDD3V3_OSC_200M ; 2 = XP3R3V
L15  FERRITEBEAD  120OHM 25%  pkg SMC_0603R_H030  page 22 : 1 = XP5R0V ; 2 = XP5R0V_VCC_ANT
L16  FERRITEBEAD  120OHM 25%  pkg SMC_0603R_H030  page 22 : 1 = XP3R3V_GPS ; 2 = XP3R3V_FPGA
L17  FERRITEBEAD  600OHM 25%  pkg SMC_0603R_H037  page 18 : 1 = XP3R3V_FPGA ; 2 = VDD3V3_SHT31A
L18  FERRITEBEAD  600OHM 25%  pkg SMC_0603R_H037  page 19 : 1 = XP1R8V_FPGA ; 2 = XP1R8V_ICP10100
L19  FERRITEBEAD  600OHM 25%  pkg SMC_0603R_H037  page 20 : 1 = VDD_BNO085 ; 2 = XP3R3V_FPGA
L20  FERRITEBEAD  26OHM 25%  pkg SMC_0603R_H030  page 27 : 1 = XP12R0V_PCIE ; 2 = XP12R0V_IN
L21  FERRITEBEAD  26OHM 25%  pkg SMC_0603R_H030  page 9 : 1 = XP3R3V_PCIE ; 2 = XP3R3V
L22  FERRITEBEAD  600OHM 25%  pkg SMC_0603R_H037  page 24 : 1 = XP3R3V_FT4232 ; 2 = XP3R3V_VPHY
L23  FERRITEBEAD  26OHM 25%  pkg SMC_0603R_H030  page 33 : 1 = UNNAMED_525_CAPACITOR_I7_1 ; 2 = UNNAMED_525_CAPACITOR_I16_1
L24  FERRITEBEAD  120OHM 25%  pkg SMC_0603R_H030  page 33 : 1 = XP3R3V_FPGA ; 2 = XP3R3V_FT4232
L33  FERRITEBEAD  120OHM 25%  pkg SMC_0603R_H030  page 14 : 1 = XP1R8V_FPGA_VCCAUX ; 2 = XP1R8V_FPGA
L34  FERRITEBEAD  120OHM 25%  pkg SMC_0603R_H030  page 14 : 1 = XP1R0V_FPGA_MGTAVCC ; 2 = XP1R0V_FPGA
L35  FERRITEBEAD  120OHM 25%  pkg SMC_0603R_H030  page 14 : 1 = FPGA_MGTAVTT ; 2 = XP1R2V_FPGA
MAC_PIN1  NUT  pkg P_NUT_079C100  page 21 : 1 = ANALOG_TUNING_IN
MAC_PIN2  NUT  pkg P_NUT_079C100  page 21 : 1 = SG
MAC_PIN3  NUT  pkg P_NUT_079C100  page 21 : 1 = R_MAC_10MHZ_RF_OUT
MAC_PIN4  NUT  pkg P_NUT_079C100  page 21 : 1 = SG
MAC_PIN5  NUT  pkg P_NUT_079C100  page 21 : 1 = XP5R0V_MAC
MAC_PIN6  NUT  pkg P_NUT_079C100  page 21 : 1 = R_MAC_BITEOUT
MAC_PIN7  NUT  pkg P_NUT_079C100  page 21 : 1 = R_MAC_UART_TX_FPGA_RX
MAC_PIN8  NUT  pkg P_NUT_079C100  page 21 : 1 = R_MAC_UART_RX_FPGA_TX
ME1  NUT  pkg P_NUT_166CT244CB198_V1_H380  page 34 : 1 = SG
ME2  NUT  pkg P_NUT_166CT244CB198_V1_H380  page 34 : 1 = SG
ME3  NUT  pkg P_NUT_166CT244CB198_V1_H380  page 34 : 1 = SG
ME4  NUT  pkg P_NUT_166CT244CB198_V1_H380  page 34 : 1 = SG
ME5  MEC_NPTH  pkg MTH100C240N  page 34
ME6  MEC_NPTH  pkg MTH100C240N  page 34
ME7  MEC_NPTH  pkg MTH100C240N  page 34
ME8  MEC_NPTH  pkg MTH100C240N  page 34

ME9  MEC_MTH8  pkg MTH125C236N_V8  page 34
  1  \1\  UNSPEC  = SG
  2  \2\  UNSPEC  = SG
  3  \3\  UNSPEC  = SG
  4  \4\  UNSPEC  = SG
  5  \5\  UNSPEC  = SG
  6  \6\  UNSPEC  = SG
  7  \7\  UNSPEC  = SG
  8  \8\  UNSPEC  = SG

ME10  MEC_MTH8  pkg MTH125C236N_V8  page 34
  1  \1\  UNSPEC  = SG
  2  \2\  UNSPEC  = SG
  3  \3\  UNSPEC  = SG
  4  \4\  UNSPEC  = SG
  5  \5\  UNSPEC  = SG
  6  \6\  UNSPEC  = SG
  7  \7\  UNSPEC  = SG
  8  \8\  UNSPEC  = SG

ME11  MEC_MTH8  pkg MTH125C236N_V8  page 34
  1  \1\  UNSPEC  = SG
  2  \2\  UNSPEC  = SG
  3  \3\  UNSPEC  = SG
  4  \4\  UNSPEC  = SG
  5  \5\  UNSPEC  = SG
  6  \6\  UNSPEC  = SG
  7  \7\  UNSPEC  = SG
  8  \8\  UNSPEC  = SG

ME12  MEC_MTH8  pkg MTH125C236N_V8  page 34
  1  \1\  UNSPEC  = SG
  2  \2\  UNSPEC  = SG
  3  \3\  UNSPEC  = SG
  4  \4\  UNSPEC  = SG
  5  \5\  UNSPEC  = SG
  6  \6\  UNSPEC  = SG
  7  \7\  UNSPEC  = SG
  8  \8\  UNSPEC  = SG

P1  CONN_HDR_2X10_M_S_SMT  52991-0208  pkg S_M_H_2X10_S_P0197  page 21
  1  \1\  BI  = R_MAC_PPS_IN1P
  2  \2\  BI  = R_MAC_USB_DP
  3  \3\  BI  = R_MAC_PPS_IN1N
  4  \4\  BI  = R_MAC_USB_DM
  5  \5\  BI  = R_MAC_PPS_IN0P
  6  \6\  BI  = XP5R0V_MAC_USB
  7  \7\  BI  = R_MAC_PPS_IN0N
  8  \8\  BI  = SG
  9  \9\  BI  = SG
  10  \10\  BI  = NC
  11  \11\  BI  = NC
  12  \12\  BI  = NC
  13  \13\  BI  = NC
  14  \14\  BI  = NC
  15  \15\  BI  = SG
  16  \16\  BI  = NC
  17  \17\  BI  = R_MAC_PPS_OUTP
  18  \18\  BI  = NC
  19  \19\  BI  = R_MAC_PPS_OUTN
  20  \20\  BI  = MAC_ALARM

P2  CONN_HDR_2X4_F_S_SMT  SQW-104-01-F-D-VS-K-TR  pkg S_F_H_2X4_S_P0787_V1  page 22
  1  \1\  BI  = XP5R0V_VCC_ANT
  2  \2\  BI  = XP3R3V_GPS
  3  \3\  BI  = GPS_UART_TXD
  4  \4\  BI  = GPS_RST_N
  5  \5\  BI  = GPS_UART_RXD
  6  \6\  BI  = GPSTP1_OUT
  7  \7\  BI  = GPSTP2_OUT
  8  \8\  BI  = SG

P3  CONN_HDR_2X3_M_RA_TH  pkg P_M_H_2X3_NP2_RA_P165_V1  page 27
  1  \1\  BI  = XP12R0V_EXT
  2  \2\  BI  = XP12R0V_EXT
  3  \3\  BI  = XP12R0V_EXT
  4  \4\  BI  = SG
  5  \5\  BI  = SG
  6  \6\  BI  = SG

Q1  POWERMOS_3P_NCH_V1  pkg SOT23_V1_H044  page 24
  1  G  BI  = FT_USB_DETECT
  2  S  BI  = SG
  3  D  BI  = UNNAMED_524_POWERMOS3PNCHV1_I44

Q2  POWERMOS_3P_NCH_V1  pkg SOT23_V1_H044  page 21
  1  G  BI  = USB_PWR_EN
  2  S  BI  = SG
  3  D  BI  = UNNAMED_527_POWERMOS3PNCHV1_I23

Q3  POWERMOS_3P_PCH  pkg SOT23_V1_H045  page 21
  1  G  BI  = UNNAMED_527_POWERMOS3PNCHV1_I23
  2  S  BI  = XP5R0V_MAC
  3  D  BI  = UNNAMED_527_FUSE_I244_1

R1  RESISTOR  330OHM 1%  pkg SMC_0402R_H016  page 16 : 1 = FPGA_OUT_SN_EEPROM_WP ; 2 = SN_EEPROM_WP
R2  RESISTOR  330OHM 1%  pkg SMC_0402R_H016  page 16 : 1 = FPGA_OUT_SEC_EEPROM_WP ; 2 = SEC_EEPROM_WP
R3  RESISTOR  4.7KOHM 1%  pkg SMC_0402R_H016  page 16 : 1 = XP3R3V_FPGA ; 2 = SEC_EEPROM_WP
R4  RESISTOR  10KOHM 1%  pkg SMC_0402R_H016  page 27 : 1 = XP12R0V_IN ; 2 = XP12R0V_A_EN
R5  RESISTOR  10KOHM 1%  pkg SMC_0402R_H016  page 27 : 1 = XP12R0V_A_EN ; 2 = SG
R6  RESISTOR  20OHM 1%  pkg SMC_0402R_H016  page 32 : 1 = XP5R0V ; 2 = UNNAMED_516_CAPACITOR_I29_1
R7  RESISTOR  0OHM -  pkg SMC_0402R_H016  page 27 : 1 = SG ; 2 = UNNAMED_15_MP5022CGQVZQFN22_I_2
R8  RESISTOR  0OHM -  pkg SMC_0402R_H016  page 27 : 1 = SG ; 2 = UNNAMED_15_MP5022CGQVZQFN22_I21
R9  RESISTOR  49.9OHM 1%  pkg SMC_0603R_H022  page 27 : 1 = XP12R0V_IN ; 2 = XP12R0V_A_AVIN
R10  RESISTOR  10KOHM 1%  pkg SMC_0402R_H016  page 27 : 1 = XP12R0V_A_IMON ; 2 = SG
R11  RESISTOR  120KOHM 1%  pkg SMC_0402R_H016  page 27 : 1 = XP12R0V_IN ; 2 = XP12R0V_A_OV
R12  RESISTOR  10KOHM 1%  pkg SMC_0402R_H016  page 27 : 1 = XP12R0V_A_OV ; 2 = SG
R13  RESISTOR  10KOHM 1%  pkg SMC_0402R_H016  page 27 : 1 = XP12R0V ; 2 = XP12R0V_A_PG
R14  RESISTOR  3.92KOHM 1%  pkg SMC_0402R  page 27 : 1 = XP12R0V_A_PG ; 2 = SG
